# S9S_MB_2U (Grand Teton) — schematic netlist excerpt (pin names and nets, part order shuffled) for the footprints in the layout excerpt that follows; sources: Cadence DE-HDL packaged netlist, KiCad conversion of 03242023_DA0F0TMBIJ0_F0T_Motherboard_J_brd_V01_OCP.brd

C17  Q_CAP  2.2UF 6.3V 20% X6S  pkg C0402  page 87 : A = P3V3_AUX ; B = GND
R91  Q_RES  240 1% EMPTY  pkg 0402LF  page 126 : A = PVNN_TERM_CPU1 ; B = PU_CPU1_UPI1_AC_COUPLING

(kicad_pcb
	(version 20260206)
	(generator "pcbnew")
	(generator_version "10.0")
	(general
		(thickness 1.6)
		(legacy_teardrops no)
	)
	(paper "A4")
	(title_block
		(title "03242023_DA0F0TMBIJ0_F0T_Motherboard_J_brd_V01_OCP.brd")
		(comment 1 "Grand Teton / footprints 5430-5431 of 6105")
	)
	(layers
		(0 "F.Cu" signal "TOP")
		(4 "In1.Cu" signal "GND")
		(6 "In2.Cu" signal "IN1")
		(8 "In3.Cu" signal "GND1")
		(10 "In4.Cu" signal "IN2")
		(12 "In5.Cu" signal "GND2")
		(14 "In6.Cu" signal "IN3")
		(16 "In7.Cu" signal "GND3")
		(18 "In8.Cu" signal "VCC")
		(20 "In9.Cu" signal "VCC1")
		(22 "In10.Cu" signal "GND4")
		(24 "In11.Cu" signal "IN4")
		(26 "In12.Cu" signal "GND5")
		(28 "In13.Cu" signal "IN5")
		(30 "In14.Cu" signal "GND6")
		(32 "In15.Cu" signal "IN6")
		(34 "In16.Cu" signal "GND7")
		(2 "B.Cu" signal "BOTTOM")
		(9 "F.Adhes" user "F.Adhesive")
		(11 "B.Adhes" user "B.Adhesive")
		(13 "F.Paste" user "Package Geometry/Pastemask Top")
		(15 "B.Paste" user "Package Geometry/Pastemask Bottom")
		(5 "F.SilkS" user "Ref Des/Silkscreen Top")
		(7 "B.SilkS" user "Ref Des/Silkscreen Bottom")
		(1 "F.Mask" user "Board Geometry/Soldermask Top")
		(3 "B.Mask" user "Board Geometry/Soldermask Bottom")
		(17 "Dwgs.User" user "User.Drawings")
		(19 "Cmts.User" user "User.Comments")
		(21 "Eco1.User" user "User.Eco1")
		(23 "Eco2.User" user "User.Eco2")
		(25 "Edge.Cuts" user "Board Geometry/Outline")
		(27 "Margin" user)
		(31 "F.CrtYd" user "Package Geometry/Place Bound Top")
		(29 "B.CrtYd" user "Package Geometry/Place Bound Bottom")
		(35 "F.Fab" user "Ref Des/Assembly Top")
		(33 "B.Fab" user "Ref Des/Assembly Bottom")
	)
	(footprint ""
		(layer "B.Cu")
		(at 155.38704 -189.34938 -90)
		(property "Reference" "R91"
			(at 0 0 90)
			(layer "B.SilkS")
			(hide yes)
			(effects
				(font
					(size 1.27 1.27)
				)
				(justify mirror)
			)
		)
		(property "Value" ""
			(at 0 0 90)
			(layer "B.Fab")
			(effects
				(font
					(size 1.27 1.27)
				)
				(justify mirror)
			)
		)
		(duplicate_pad_numbers_are_jumpers no)
		(fp_line
			(start -0.7874 0.4064)
			(end 0.7874 0.4064)
			(stroke
				(width 0.1524)
				(type default)
			)
			(layer "B.SilkS")
		)
		(fp_line
			(start 0.7874 0.4064)
			(end 0.7874 -0.4064)
			(stroke
				(width 0.1524)
				(type default)
			)
			(layer "B.SilkS")
		)
		(fp_line
			(start -0.7874 -0.4064)
			(end -0.7874 0.4064)
			(stroke
				(width 0.1524)
				(type default)
			)
			(layer "B.SilkS")
		)
		(fp_line
			(start 0.7874 -0.4064)
			(end -0.7874 -0.4064)
			(stroke
				(width 0.1524)
				(type default)
			)
			(layer "B.SilkS")
		)
		(fp_line
			(start -0.67945 0.3048)
			(end -0.120396 0.3048)
			(stroke
				(width 0.1)
				(type default)
			)
			(layer "B.Fab")
		)
		(fp_line
			(start -0.120396 0.3048)
			(end -0.120396 0.2794)
			(stroke
				(width 0.1)
				(type default)
			)
			(layer "B.Fab")
		)
		(fp_line
			(start 0.12065 0.3048)
			(end 0.67945 0.3048)
			(stroke
				(width 0.1)
				(type default)
			)
			(layer "B.Fab")
		)
		(fp_line
			(start 0.67945 0.3048)
			(end 0.67945 -0.305054)
			(stroke
				(width 0.1)
				(type default)
			)
			(layer "B.Fab")
		)
		(fp_line
			(start -0.120396 0.2794)
			(end 0.12065 0.2794)
			(stroke
				(width 0.1)
				(type default)
			)
			(layer "B.Fab")
		)
		(fp_line
			(start 0.12065 0.2794)
			(end 0.12065 0.3048)
			(stroke
				(width 0.1)
				(type default)
			)
			(layer "B.Fab")
		)
		(fp_line
			(start -0.12065 -0.2794)
			(end -0.12065 -0.3048)
			(stroke
				(width 0.1)
				(type default)
			)
			(layer "B.Fab")
		)
		(fp_line
			(start 0.12065 -0.2794)
			(end -0.12065 -0.2794)
			(stroke
				(width 0.1)
				(type default)
			)
			(layer "B.Fab")
		)
		(fp_line
			(start -0.67945 -0.3048)
			(end -0.67945 0.3048)
			(stroke
				(width 0.1)
				(type default)
			)
			(layer "B.Fab")
		)
		(fp_line
			(start -0.12065 -0.3048)
			(end -0.67945 -0.3048)
			(stroke
				(width 0.1)
				(type default)
			)
			(layer "B.Fab")
		)
		(fp_line
			(start 0.12065 -0.305054)
			(end 0.12065 -0.2794)
			(stroke
				(width 0.1)
				(type default)
			)
			(layer "B.Fab")
		)
		(fp_line
			(start 0.67945 -0.305054)
			(end 0.12065 -0.305054)
			(stroke
				(width 0.1)
				(type default)
			)
			(layer "B.Fab")
		)
		(pad "1" smd circle
			(at 0.40005 0 90)
			(size 0 0)
			(layers "B.Cu" "B.Mask" "B.Paste")
			(net "PVNN_TERM_CPU1")
		)
		(pad "2" smd circle
			(at -0.40005 0 90)
			(size 0 0)
			(layers "B.Cu" "B.Mask" "B.Paste")
			(net "PU_CPU1_UPI1_AC_COUPLING")
		)
	)
	(footprint ""
		(layer "B.Cu")
		(at 278.724614 -319.263776 180)
		(property "Reference" "C17"
			(at 0 0 0)
			(layer "B.SilkS")
			(hide yes)
			(effects
				(font
					(size 1.27 1.27)
				)
				(justify mirror)
			)
		)
		(property "Value" ""
			(at 0 0 0)
			(layer "B.Fab")
			(effects
				(font
					(size 1.27 1.27)
				)
				(justify mirror)
			)
		)
		(duplicate_pad_numbers_are_jumpers no)
		(fp_line
			(start 0.7874 0.4064)
			(end 0.7874 -0.4064)
			(stroke
				(width 0.1524)
				(type default)
			)
			(layer "B.SilkS")
		)
		(fp_line
			(start 0.7874 -0.4064)
			(end -0.7874 -0.4064)
			(stroke
				(width 0.1524)
				(type default)
			)
			(layer "B.SilkS")
		)
		(fp_line
			(start -0.7874 0.4064)
			(end 0.7874 0.4064)
			(stroke
				(width 0.1524)
				(type default)
			)
			(layer "B.SilkS")
		)
		(fp_line
			(start -0.7874 -0.4064)
			(end -0.7874 0.4064)
			(stroke
				(width 0.1524)
				(type default)
			)
			(layer "B.SilkS")
		)
		(fp_line
			(start 0.67945 0.3048)
			(end 0.67945 -0.305054)
			(stroke
				(width 0.1)
				(type default)
			)
			(layer "B.Fab")
		)
		(fp_line
			(start 0.67945 -0.305054)
			(end 0.12065 -0.305054)
			(stroke
				(width 0.1)
				(type default)
			)
			(layer "B.Fab")
		)
		(fp_line
			(start 0.12065 0.3048)
			(end 0.67945 0.3048)
			(stroke
				(width 0.1)
				(type default)
			)
			(layer "B.Fab")
		)
		(fp_line
			(start 0.12065 0.2794)
			(end 0.12065 0.3048)
			(stroke
				(width 0.1)
				(type default)
			)
			(layer "B.Fab")
		)
		(fp_line
			(start 0.12065 -0.2794)
			(end -0.12065 -0.2794)
			(stroke
				(width 0.1)
				(type default)
			)
			(layer "B.Fab")
		)
		(fp_line
			(start 0.12065 -0.305054)
			(end 0.12065 -0.2794)
			(stroke
				(width 0.1)
				(type default)
			)
			(layer "B.Fab")
		)
		(fp_line
			(start -0.120396 0.3048)
			(end -0.120396 0.2794)
			(stroke
				(width 0.1)
				(type default)
			)
			(layer "B.Fab")
		)
		(fp_line
			(start -0.120396 0.2794)
			(end 0.12065 0.2794)
			(stroke
				(width 0.1)
				(type default)
			)
			(layer "B.Fab")
		)
		(fp_line
			(start -0.12065 -0.2794)
			(end -0.12065 -0.3048)
			(stroke
				(width 0.1)
				(type default)
			)
			(layer "B.Fab")
		)
		(fp_line
			(start -0.12065 -0.3048)
			(end -0.67945 -0.3048)
			(stroke
				(width 0.1)
				(type default)
			)
			(layer "B.Fab")
		)
		(fp_line
			(start -0.67945 0.3048)
			(end -0.120396 0.3048)
			(stroke
				(width 0.1)
				(type default)
			)
			(layer "B.Fab")
		)
		(fp_line
			(start -0.67945 -0.3048)
			(end -0.67945 0.3048)
			(stroke
				(width 0.1)
				(type default)
			)
			(layer "B.Fab")
		)
		(pad "1" smd circle
			(at 0.40005 0)
			(size 0 0)
			(layers "B.Cu" "B.Mask" "B.Paste")
			(net "P3V3_AUX")
		)
		(pad "2" smd circle
			(at -0.40005 0)
			(size 0 0)
			(layers "B.Cu" "B.Mask" "B.Paste")
			(net "GND")
		)
	)
)
